(kicad_pcb
	(version 20260206)
	(generator "pcbnew")
	(generator_version "10.0")
	(general
		(thickness 1.6)
		(legacy_teardrops no)
	)
	(paper "A4")
	(title_block
		(title "baseboard — 13948-1b.1110WZS1818.brd")
		(comment 1 "Honey Badger (Wiwynn) / footprints 168-174 of 2523")
	)
	(layers
		(0 "F.Cu" signal "TOP")
		(4 "In1.Cu" signal "L2GND")
		(6 "In2.Cu" signal "L3")
		(8 "In3.Cu" signal "L4VCC")
		(10 "In4.Cu" signal "L5VCC")
		(12 "In5.Cu" signal "L6")
		(14 "In6.Cu" signal "L7GND")
		(2 "B.Cu" signal "BOTTOM")
		(9 "F.Adhes" user "F.Adhesive")
		(11 "B.Adhes" user "B.Adhesive")
		(13 "F.Paste" user "Package Geometry/Pastemask Top")
		(15 "B.Paste" user "Package Geometry/Pastemask Bottom")
		(5 "F.SilkS" user "Ref Des/Silkscreen Top")
		(7 "B.SilkS" user "Ref Des/Silkscreen Bottom")
		(1 "F.Mask" user "Board Geometry/Soldermask Top")
		(3 "B.Mask" user "Board Geometry/Soldermask Bottom")
		(17 "Dwgs.User" user "User.Drawings")
		(19 "Cmts.User" user "User.Comments")
		(21 "Eco1.User" user "User.Eco1")
		(23 "Eco2.User" user "User.Eco2")
		(25 "Edge.Cuts" user "Board Geometry/Outline")
		(27 "Margin" user)
		(31 "F.CrtYd" user "Package Geometry/Place Bound Top")
		(29 "B.CrtYd" user "Package Geometry/Place Bound Bottom")
		(35 "F.Fab" user "Ref Des/Assembly Top")
		(33 "B.Fab" user "Ref Des/Assembly Bottom")
	)
	(footprint ""
		(layer "F.Cu")
		(at 331.851 -217.17 -90)
		(property "Reference" "C146"
			(at 0 0 270)
			(layer "F.SilkS")
			(hide yes)
			(effects
				(font
					(size 1.27 1.27)
				)
			)
		)
		(property "Value" "SCD1U16V2KX-3GP"
			(at 1.1811 -2.7051 270)
			(unlocked yes)
			(layer "F.Fab")
			(hide yes)
			(effects
				(font
					(size 1.016 1.016)
					(thickness 0.1524)
				)
			)
		)
		(property "Device Type" "C402H22"
			(at 1.1811 -4.2291 270)
			(unlocked yes)
			(layer "F.Fab")
			(hide yes)
			(effects
				(font
					(size 1.016 1.016)
					(thickness 0.1524)
				)
			)
		)
		(duplicate_pad_numbers_are_jumpers no)
		(fp_rect
			(start -0.4318 0.9525)
			(end 0.4318 -0.9525)
			(stroke
				(width 0)
				(type default)
			)
			(fill no)
			(layer "F.CrtYd")
		)
		(fp_rect
			(start -0.4318 0.9525)
			(end 0.4318 -0.9525)
			(stroke
				(width 0)
				(type default)
			)
			(fill no)
			(layer "F.Fab")
		)
		(pad "1" smd custom
			(at 0 -0.4445 270)
			(size 0.1524 0.1524)
			(layers "F.Cu" "F.Mask" "F.Paste")
			(net "P3V3_STBY")
			(options
				(clearance outline)
				(anchor circle)
			)
			(primitives
				(gr_poly
					(pts
						(arc
							(start 0.3048 -0.2032)
							(mid 0.275042 -0.275042)
							(end 0.2032 -0.3048)
						)
						(arc
							(start -0.2032 -0.3048)
							(mid -0.275042 -0.275042)
							(end -0.3048 -0.2032)
						)
						(arc
							(start -0.3048 0.2032)
							(mid -0.275042 0.275042)
							(end -0.2032 0.3048)
						)
						(arc
							(start 0.2032 0.3048)
							(mid 0.275042 0.275042)
							(end 0.3048 0.2032)
						)
					)
					(width 0)
					(fill yes)
				)
			)
		)
		(pad "2" smd custom
			(at 0 0.4445 270)
			(size 0.1524 0.1524)
			(layers "F.Cu" "F.Mask" "F.Paste")
			(net "GND")
			(options
				(clearance outline)
				(anchor circle)
			)
			(primitives
				(gr_poly
					(pts
						(arc
							(start 0.3048 -0.2032)
							(mid 0.275042 -0.275042)
							(end 0.2032 -0.3048)
						)
						(arc
							(start -0.2032 -0.3048)
							(mid -0.275042 -0.275042)
							(end -0.3048 -0.2032)
						)
						(arc
							(start -0.3048 0.2032)
							(mid -0.275042 0.275042)
							(end -0.2032 0.3048)
						)
						(arc
							(start 0.2032 0.3048)
							(mid 0.275042 0.275042)
							(end 0.3048 0.2032)
						)
					)
					(width 0)
					(fill yes)
				)
			)
		)
	)
	(footprint ""
		(layer "F.Cu")
		(at 166.624 -155.8036 90)
		(property "Reference" "SR728"
			(at 0 0 90)
			(layer "F.SilkS")
			(hide yes)
			(effects
				(font
					(size 1.27 1.27)
				)
			)
		)
		(property "Value" "0R2J-2-GP"
			(at 0.064008 -3.993896 90)
			(unlocked yes)
			(layer "F.Fab")
			(hide yes)
			(effects
				(font
					(size 1.016 1.016)
					(thickness 0.1524)
				)
			)
		)
		(property "Device Type" "R402H16"
			(at 0.064008 -5.517896 90)
			(unlocked yes)
			(layer "F.Fab")
			(hide yes)
			(effects
				(font
					(size 1.016 1.016)
					(thickness 0.1524)
				)
			)
		)
		(duplicate_pad_numbers_are_jumpers no)
		(fp_line
			(start 0.508 -0.9398)
			(end -0.508 -0.9398)
			(stroke
				(width 0.1524)
				(type default)
			)
			(layer "F.SilkS")
		)
		(fp_line
			(start -0.508 -0.9398)
			(end -0.508 0.9398)
			(stroke
				(width 0.1524)
				(type default)
			)
			(layer "F.SilkS")
		)
		(fp_rect
			(start -0.508 0.9398)
			(end 0.508 -0.9398)
			(stroke
				(width 0)
				(type default)
			)
			(fill no)
			(layer "F.CrtYd")
		)
		(fp_rect
			(start -0.508 0.9398)
			(end 0.508 -0.9398)
			(stroke
				(width 0)
				(type default)
			)
			(fill no)
			(layer "F.Fab")
		)
		(pad "1" smd custom
			(at 0 -0.4445 90)
			(size 0.1397 0.1397)
			(layers "F.Cu" "F.Mask" "F.Paste")
			(net "EXP_IOC_BMC_R_SCL_14")
			(options
				(clearance outline)
				(anchor circle)
			)
			(primitives
				(gr_poly
					(pts
						(arc
							(start -0.1778 -0.2794)
							(mid -0.249642 -0.249642)
							(end -0.2794 -0.1778)
						)
						(arc
							(start -0.2794 0.1778)
							(mid -0.249642 0.249642)
							(end -0.1778 0.2794)
						)
						(arc
							(start 0.1778 0.2794)
							(mid 0.249642 0.249642)
							(end 0.2794 0.1778)
						)
						(arc
							(start 0.2794 -0.1778)
							(mid 0.249642 -0.249642)
							(end 0.1778 -0.2794)
						)
					)
					(width 0)
					(fill yes)
				)
			)
		)
		(pad "2" smd custom
			(at 0 0.4445 90)
			(size 0.1397 0.1397)
			(layers "F.Cu" "F.Mask" "F.Paste")
			(net "EXP_IOC_BMC_SCL_14")
			(options
				(clearance outline)
				(anchor circle)
			)
			(primitives
				(gr_poly
					(pts
						(arc
							(start -0.1778 -0.2794)
							(mid -0.249642 -0.249642)
							(end -0.2794 -0.1778)
						)
						(arc
							(start -0.2794 0.1778)
							(mid -0.249642 0.249642)
							(end -0.1778 0.2794)
						)
						(arc
							(start 0.1778 0.2794)
							(mid 0.249642 0.249642)
							(end 0.2794 0.1778)
						)
						(arc
							(start 0.2794 -0.1778)
							(mid 0.249642 -0.249642)
							(end 0.1778 -0.2794)
						)
					)
					(width 0)
					(fill yes)
				)
			)
		)
	)
	(footprint ""
		(layer "F.Cu")
		(at 184.785 -118.826788)
		(property "Reference" "U32"
			(at 0 0 0)
			(layer "F.SilkS")
			(hide yes)
			(effects
				(font
					(size 1.27 1.27)
				)
			)
		)
		(property "Value" "SN74LVC1G07DCKRG4-2-GP"
			(at -2.3368 -8.6868 0)
			(unlocked yes)
			(layer "F.Fab")
			(hide yes)
			(effects
				(font
					(size 1.016 1.016)
					(thickness 0.1524)
				)
			)
		)
		(property "Device Type" "SC70-5H44"
			(at -2.3114 -10.414 0)
			(unlocked yes)
			(layer "F.Fab")
			(hide yes)
			(effects
				(font
					(size 1.016 1.016)
					(thickness 0.1524)
				)
			)
		)
		(duplicate_pad_numbers_are_jumpers no)
		(fp_line
			(start -1.27 -1.7018)
			(end 1.27 -1.7018)
			(stroke
				(width 0.1524)
				(type default)
			)
			(layer "F.SilkS")
		)
		(fp_line
			(start -1.27 1.7018)
			(end -1.27 -1.7018)
			(stroke
				(width 0.1524)
				(type default)
			)
			(layer "F.SilkS")
		)
		(fp_line
			(start 0.6604 -1.8034)
			(end 1.3843 -1.8034)
			(stroke
				(width 0.3302)
				(type default)
			)
			(layer "F.SilkS")
		)
		(fp_line
			(start 1.27 -1.7018)
			(end 1.27 1.7018)
			(stroke
				(width 0.1524)
				(type default)
			)
			(layer "F.SilkS")
		)
		(fp_line
			(start 1.27 1.7018)
			(end -1.27 1.7018)
			(stroke
				(width 0.1524)
				(type default)
			)
			(layer "F.SilkS")
		)
		(fp_line
			(start 1.3843 -1.8034)
			(end 1.3843 -1.1176)
			(stroke
				(width 0.3302)
				(type default)
			)
			(layer "F.SilkS")
		)
		(fp_rect
			(start -1.524 1.9558)
			(end 1.524 -1.9558)
			(stroke
				(width 0)
				(type default)
			)
			(fill no)
			(layer "F.CrtYd")
		)
		(fp_poly
			(pts
				(xy -1.524 -1.9558) (xy 1.524 -1.9558) (xy 1.524 1.9558) (xy -1.524 1.9558)
			)
			(stroke
				(width 0)
				(type default)
			)
			(fill no)
			(layer "F.Fab")
		)
		(pad "1" smd rect
			(at 0.65024 -0.8255)
			(size 0.4064 1.2192)
			(layers "F.Cu" "F.Mask" "F.Paste")
			(net "Net_215")
		)
		(pad "2" smd rect
			(at 0 -0.8255)
			(size 0.4064 1.2192)
			(layers "F.Cu" "F.Mask" "F.Paste")
			(net "PMU_PLTRST#")
		)
		(pad "3" smd rect
			(at -0.65024 -0.8255)
			(size 0.4064 1.2192)
			(layers "F.Cu" "F.Mask" "F.Paste")
			(net "GND")
		)
		(pad "4" smd rect
			(at -0.65024 0.8255)
			(size 0.4064 1.2192)
			(layers "F.Cu" "F.Mask" "F.Paste")
			(net "PMU_PLTRST_N")
		)
		(pad "5" smd rect
			(at 0.65024 0.8255)
			(size 0.4064 1.2192)
			(layers "F.Cu" "F.Mask" "F.Paste")
			(net "P3V3_STBY")
		)
	)
	(footprint ""
		(layer "F.Cu")
		(at 91.929966 -63.119)
		(property "Reference" "SR674"
			(at 0 0 0)
			(layer "F.SilkS")
			(hide yes)
			(effects
				(font
					(size 1.27 1.27)
				)
			)
		)
		(property "Value" "4K7R2F-GP"
			(at 0.064008 -3.993896 0)
			(unlocked yes)
			(layer "F.Fab")
			(hide yes)
			(effects
				(font
					(size 1.016 1.016)
					(thickness 0.1524)
				)
			)
		)
		(property "Device Type" "R402H16"
			(at 0.064008 -5.517896 0)
			(unlocked yes)
			(layer "F.Fab")
			(hide yes)
			(effects
				(font
					(size 1.016 1.016)
					(thickness 0.1524)
				)
			)
		)
		(duplicate_pad_numbers_are_jumpers no)
		(fp_line
			(start -0.508 -0.9398)
			(end -0.508 0.9398)
			(stroke
				(width 0.1524)
				(type default)
			)
			(layer "F.SilkS")
		)
		(fp_line
			(start 0.508 -0.9398)
			(end -0.508 -0.9398)
			(stroke
				(width 0.1524)
				(type default)
			)
			(layer "F.SilkS")
		)
		(fp_rect
			(start -0.508 0.9398)
			(end 0.508 -0.9398)
			(stroke
				(width 0)
				(type default)
			)
			(fill no)
			(layer "F.CrtYd")
		)
		(fp_rect
			(start -0.508 0.9398)
			(end 0.508 -0.9398)
			(stroke
				(width 0)
				(type default)
			)
			(fill no)
			(layer "F.Fab")
		)
		(pad "1" smd custom
			(at 0 -0.4445)
			(size 0.1397 0.1397)
			(layers "F.Cu" "F.Mask" "F.Paste")
			(net "P1V8_C")
			(options
				(clearance outline)
				(anchor circle)
			)
			(primitives
				(gr_poly
					(pts
						(arc
							(start -0.1778 -0.2794)
							(mid -0.249642 -0.249642)
							(end -0.2794 -0.1778)
						)
						(arc
							(start -0.2794 0.1778)
							(mid -0.249642 0.249642)
							(end -0.1778 0.2794)
						)
						(arc
							(start 0.1778 0.2794)
							(mid 0.249642 0.249642)
							(end 0.2794 0.1778)
						)
						(arc
							(start 0.2794 -0.1778)
							(mid 0.249642 -0.249642)
							(end 0.1778 -0.2794)
						)
					)
					(width 0)
					(fill yes)
				)
			)
		)
		(pad "2" smd custom
			(at 0 0.4445)
			(size 0.1397 0.1397)
			(layers "F.Cu" "F.Mask" "F.Paste")
			(net "ICE1_TMS")
			(options
				(clearance outline)
				(anchor circle)
			)
			(primitives
				(gr_poly
					(pts
						(arc
							(start -0.1778 -0.2794)
							(mid -0.249642 -0.249642)
							(end -0.2794 -0.1778)
						)
						(arc
							(start -0.2794 0.1778)
							(mid -0.249642 0.249642)
							(end -0.1778 0.2794)
						)
						(arc
							(start 0.1778 0.2794)
							(mid 0.249642 0.249642)
							(end 0.2794 0.1778)
						)
						(arc
							(start 0.2794 -0.1778)
							(mid 0.249642 -0.249642)
							(end 0.1778 -0.2794)
						)
					)
					(width 0)
					(fill yes)
				)
			)
		)
	)
	(footprint ""
		(layer "F.Cu")
		(at 334.518 -83.947 180)
		(property "Reference" "R294"
			(at 0 0 180)
			(layer "F.SilkS")
			(hide yes)
			(effects
				(font
					(size 1.27 1.27)
				)
			)
		)
		(property "Value" "0R0402-PAD-1-GP"
			(at 0.064008 -3.993896 180)
			(unlocked yes)
			(layer "F.Fab")
			(hide yes)
			(effects
				(font
					(size 1.016 1.016)
					(thickness 0.1524)
				)
			)
		)
		(property "Device Type" "0R0402-PAD"
			(at 0.064008 -5.517896 180)
			(unlocked yes)
			(layer "F.Fab")
			(hide yes)
			(effects
				(font
					(size 1.016 1.016)
					(thickness 0.1524)
				)
			)
		)
		(duplicate_pad_numbers_are_jumpers no)
		(fp_line
			(start 0.508 -0.9398)
			(end -0.508 -0.9398)
			(stroke
				(width 0.1524)
				(type default)
			)
			(layer "F.SilkS")
		)
		(fp_line
			(start -0.508 -0.9398)
			(end -0.508 0.9398)
			(stroke
				(width 0.1524)
				(type default)
			)
			(layer "F.SilkS")
		)
		(fp_rect
			(start -0.508 0.9398)
			(end 0.508 -0.9398)
			(stroke
				(width 0)
				(type default)
			)
			(fill no)
			(layer "F.CrtYd")
		)
		(fp_rect
			(start -0.508 0.9398)
			(end 0.508 -0.9398)
			(stroke
				(width 0)
				(type default)
			)
			(fill no)
			(layer "F.Fab")
		)
		(pad "1" smd custom
			(at 0 -0.4445 180)
			(size 0.1397 0.1397)
			(layers "F.Cu" "F.Mask" "F.Paste")
			(net "ROMD2_R")
			(options
				(clearance outline)
				(anchor circle)
			)
			(primitives
				(gr_poly
					(pts
						(xy -0.2794 0.3683)
						(arc
							(start -0.2794 -0.2667)
							(mid -0.249642 -0.338542)
							(end -0.1778 -0.3683)
						)
						(arc
							(start 0.1778 -0.3683)
							(mid 0.249642 -0.338542)
							(end 0.2794 -0.2667)
						)
						(xy 0.2794 0.3683)
					)
					(width 0)
					(fill yes)
				)
			)
		)
		(pad "2" smd custom
			(at 0 0.4445 180)
			(size 0.1397 0.1397)
			(layers "F.Cu" "F.Mask" "F.Paste")
			(net "ROMD2")
			(options
				(clearance outline)
				(anchor circle)
			)
			(primitives
				(gr_poly
					(pts
						(arc
							(start -0.1778 0.3683)
							(mid -0.249642 0.338542)
							(end -0.2794 0.2667)
						)
						(xy -0.2794 -0.3683) (xy 0.2794 -0.3683)
						(arc
							(start 0.2794 0.2667)
							(mid 0.249642 0.338542)
							(end 0.1778 0.3683)
						)
					)
					(width 0)
					(fill yes)
				)
			)
		)
	)
	(footprint ""
		(layer "F.Cu")
		(at 306.578 -205.105)
		(property "Reference" "R5300"
			(at 0 0 0)
			(layer "F.SilkS")
			(hide yes)
			(effects
				(font
					(size 1.27 1.27)
				)
			)
		)
		(property "Value" "0R2J-2-GP"
			(at 0.064008 -3.993896 0)
			(unlocked yes)
			(layer "F.Fab")
			(hide yes)
			(effects
				(font
					(size 1.016 1.016)
					(thickness 0.1524)
				)
			)
		)
		(property "Device Type" "R402H16"
			(at 0.064008 -5.517896 0)
			(unlocked yes)
			(layer "F.Fab")
			(hide yes)
			(effects
				(font
					(size 1.016 1.016)
					(thickness 0.1524)
				)
			)
		)
		(duplicate_pad_numbers_are_jumpers no)
		(fp_line
			(start -0.508 -0.9398)
			(end -0.508 0.9398)
			(stroke
				(width 0.1524)
				(type default)
			)
			(layer "F.SilkS")
		)
		(fp_line
			(start 0.508 -0.9398)
			(end -0.508 -0.9398)
			(stroke
				(width 0.1524)
				(type default)
			)
			(layer "F.SilkS")
		)
		(fp_rect
			(start -0.508 0.9398)
			(end 0.508 -0.9398)
			(stroke
				(width 0)
				(type default)
			)
			(fill no)
			(layer "F.CrtYd")
		)
		(fp_rect
			(start -0.508 0.9398)
			(end 0.508 -0.9398)
			(stroke
				(width 0)
				(type default)
			)
			(fill no)
			(layer "F.Fab")
		)
		(pad "1" smd custom
			(at 0 -0.4445)
			(size 0.1397 0.1397)
			(layers "F.Cu" "F.Mask" "F.Paste")
			(net "BMC_I2C_SDA_10")
			(options
				(clearance outline)
				(anchor circle)
			)
			(primitives
				(gr_poly
					(pts
						(arc
							(start -0.1778 -0.2794)
							(mid -0.249642 -0.249642)
							(end -0.2794 -0.1778)
						)
						(arc
							(start -0.2794 0.1778)
							(mid -0.249642 0.249642)
							(end -0.1778 0.2794)
						)
						(arc
							(start 0.1778 0.2794)
							(mid 0.249642 0.249642)
							(end 0.2794 0.1778)
						)
						(arc
							(start 0.2794 -0.1778)
							(mid 0.249642 -0.249642)
							(end 0.1778 -0.2794)
						)
					)
					(width 0)
					(fill yes)
				)
			)
		)
		(pad "2" smd custom
			(at 0 0.4445)
			(size 0.1397 0.1397)
			(layers "F.Cu" "F.Mask" "F.Paste")
			(net "LED_DR_I2C_SDA")
			(options
				(clearance outline)
				(anchor circle)
			)
			(primitives
				(gr_poly
					(pts
						(arc
							(start -0.1778 -0.2794)
							(mid -0.249642 -0.249642)
							(end -0.2794 -0.1778)
						)
						(arc
							(start -0.2794 0.1778)
							(mid -0.249642 0.249642)
							(end -0.1778 0.2794)
						)
						(arc
							(start 0.1778 0.2794)
							(mid 0.249642 0.249642)
							(end 0.2794 0.1778)
						)
						(arc
							(start 0.2794 -0.1778)
							(mid 0.249642 -0.249642)
							(end 0.1778 -0.2794)
						)
					)
					(width 0)
					(fill yes)
				)
			)
		)
	)
	(footprint ""
		(layer "F.Cu")
		(at 266.065 -180.086 90)
		(property "Reference" "R341"
			(at 0 0 90)
			(layer "F.SilkS")
			(hide yes)
			(effects
				(font
					(size 1.27 1.27)
				)
			)
		)
		(property "Value" "3K3R2F-2-GP"
			(at 0.064008 -3.993896 90)
			(unlocked yes)
			(layer "F.Fab")
			(hide yes)
			(effects
				(font
					(size 1.016 1.016)
					(thickness 0.1524)
				)
			)
		)
		(property "Device Type" "R402H16"
			(at 0.064008 -5.517896 90)
			(unlocked yes)
			(layer "F.Fab")
			(hide yes)
			(effects
				(font
					(size 1.016 1.016)
					(thickness 0.1524)
				)
			)
		)
		(duplicate_pad_numbers_are_jumpers no)
		(fp_line
			(start 0.508 -0.9398)
			(end -0.508 -0.9398)
			(stroke
				(width 0.1524)
				(type default)
			)
			(layer "F.SilkS")
		)
		(fp_line
			(start -0.508 -0.9398)
			(end -0.508 0.9398)
			(stroke
				(width 0.1524)
				(type default)
			)
			(layer "F.SilkS")
		)
		(fp_rect
			(start -0.508 0.9398)
			(end 0.508 -0.9398)
			(stroke
				(width 0)
				(type default)
			)
			(fill no)
			(layer "F.CrtYd")
		)
		(fp_rect
			(start -0.508 0.9398)
			(end 0.508 -0.9398)
			(stroke
				(width 0)
				(type default)
			)
			(fill no)
			(layer "F.Fab")
		)
		(pad "1" smd custom
			(at 0 -0.4445 90)
			(size 0.1397 0.1397)
			(layers "F.Cu" "F.Mask" "F.Paste")
			(net "P3V3_STBY")
			(options
				(clearance outline)
				(anchor circle)
			)
			(primitives
				(gr_poly
					(pts
						(arc
							(start -0.1778 -0.2794)
							(mid -0.249642 -0.249642)
							(end -0.2794 -0.1778)
						)
						(arc
							(start -0.2794 0.1778)
							(mid -0.249642 0.249642)
							(end -0.1778 0.2794)
						)
						(arc
							(start 0.1778 0.2794)
							(mid 0.249642 0.249642)
							(end 0.2794 0.1778)
						)
						(arc
							(start 0.2794 -0.1778)
							(mid 0.249642 -0.249642)
							(end 0.1778 -0.2794)
						)
					)
					(width 0)
					(fill yes)
				)
			)
		)
		(pad "2" smd custom
			(at 0 0.4445 90)
			(size 0.1397 0.1397)
			(layers "F.Cu" "F.Mask" "F.Paste")
			(net "ROMA16")
			(options
				(clearance outline)
				(anchor circle)
			)
			(primitives
				(gr_poly
					(pts
						(arc
							(start -0.1778 -0.2794)
							(mid -0.249642 -0.249642)
							(end -0.2794 -0.1778)
						)
						(arc
							(start -0.2794 0.1778)
							(mid -0.249642 0.249642)
							(end -0.1778 0.2794)
						)
						(arc
							(start 0.1778 0.2794)
							(mid 0.249642 0.249642)
							(end 0.2794 0.1778)
						)
						(arc
							(start 0.2794 -0.1778)
							(mid 0.249642 -0.249642)
							(end 0.1778 -0.2794)
						)
					)
					(width 0)
					(fill yes)
				)
			)
		)
	)
)
